(kicad_pcb
	(version 20260206)
	(generator "pcbnew")
	(generator_version "10.0")
	(general
		(thickness 1.6)
		(legacy_teardrops no)
	)
	(paper "A4")
	(title_block
		(title "03242023_DA0F0TMBIJ0_F0T_Motherboard_J_brd_V01_OCP.brd")
		(comment 1 "Grand Teton / footprints 5010-5015 of 6105")
	)
	(layers
		(0 "F.Cu" signal "TOP")
		(4 "In1.Cu" signal "GND")
		(6 "In2.Cu" signal "IN1")
		(8 "In3.Cu" signal "GND1")
		(10 "In4.Cu" signal "IN2")
		(12 "In5.Cu" signal "GND2")
		(14 "In6.Cu" signal "IN3")
		(16 "In7.Cu" signal "GND3")
		(18 "In8.Cu" signal "VCC")
		(20 "In9.Cu" signal "VCC1")
		(22 "In10.Cu" signal "GND4")
		(24 "In11.Cu" signal "IN4")
		(26 "In12.Cu" signal "GND5")
		(28 "In13.Cu" signal "IN5")
		(30 "In14.Cu" signal "GND6")
		(32 "In15.Cu" signal "IN6")
		(34 "In16.Cu" signal "GND7")
		(2 "B.Cu" signal "BOTTOM")
		(9 "F.Adhes" user "F.Adhesive")
		(11 "B.Adhes" user "B.Adhesive")
		(13 "F.Paste" user "Package Geometry/Pastemask Top")
		(15 "B.Paste" user "Package Geometry/Pastemask Bottom")
		(5 "F.SilkS" user "Ref Des/Silkscreen Top")
		(7 "B.SilkS" user "Ref Des/Silkscreen Bottom")
		(1 "F.Mask" user "Board Geometry/Soldermask Top")
		(3 "B.Mask" user "Board Geometry/Soldermask Bottom")
		(17 "Dwgs.User" user "User.Drawings")
		(19 "Cmts.User" user "User.Comments")
		(21 "Eco1.User" user "User.Eco1")
		(23 "Eco2.User" user "User.Eco2")
		(25 "Edge.Cuts" user "Board Geometry/Outline")
		(27 "Margin" user)
		(31 "F.CrtYd" user "Package Geometry/Place Bound Top")
		(29 "B.CrtYd" user "Package Geometry/Place Bound Bottom")
		(35 "F.Fab" user "Ref Des/Assembly Top")
		(33 "B.Fab" user "Ref Des/Assembly Bottom")
	)
	(footprint ""
		(layer "B.Cu")
		(at 178.61788 -330.495148)
		(property "Reference" "R1935"
			(at 0 0 0)
			(layer "B.SilkS")
			(hide yes)
			(effects
				(font
					(size 1.27 1.27)
				)
				(justify mirror)
			)
		)
		(property "Value" ""
			(at 0 0 0)
			(layer "B.Fab")
			(effects
				(font
					(size 1.27 1.27)
				)
				(justify mirror)
			)
		)
		(duplicate_pad_numbers_are_jumpers no)
		(fp_line
			(start -0.7874 -0.4064)
			(end -0.7874 0.4064)
			(stroke
				(width 0.1524)
				(type default)
			)
			(layer "B.SilkS")
		)
		(fp_line
			(start -0.7874 0.4064)
			(end 0.7874 0.4064)
			(stroke
				(width 0.1524)
				(type default)
			)
			(layer "B.SilkS")
		)
		(fp_line
			(start 0.7874 -0.4064)
			(end -0.7874 -0.4064)
			(stroke
				(width 0.1524)
				(type default)
			)
			(layer "B.SilkS")
		)
		(fp_line
			(start 0.7874 0.4064)
			(end 0.7874 -0.4064)
			(stroke
				(width 0.1524)
				(type default)
			)
			(layer "B.SilkS")
		)
		(fp_line
			(start -0.67945 -0.3048)
			(end -0.67945 0.3048)
			(stroke
				(width 0.1)
				(type default)
			)
			(layer "B.Fab")
		)
		(fp_line
			(start -0.67945 0.3048)
			(end -0.120396 0.3048)
			(stroke
				(width 0.1)
				(type default)
			)
			(layer "B.Fab")
		)
		(fp_line
			(start -0.12065 -0.3048)
			(end -0.67945 -0.3048)
			(stroke
				(width 0.1)
				(type default)
			)
			(layer "B.Fab")
		)
		(fp_line
			(start -0.12065 -0.2794)
			(end -0.12065 -0.3048)
			(stroke
				(width 0.1)
				(type default)
			)
			(layer "B.Fab")
		)
		(fp_line
			(start -0.120396 0.2794)
			(end 0.12065 0.2794)
			(stroke
				(width 0.1)
				(type default)
			)
			(layer "B.Fab")
		)
		(fp_line
			(start -0.120396 0.3048)
			(end -0.120396 0.2794)
			(stroke
				(width 0.1)
				(type default)
			)
			(layer "B.Fab")
		)
		(fp_line
			(start 0.12065 -0.305054)
			(end 0.12065 -0.2794)
			(stroke
				(width 0.1)
				(type default)
			)
			(layer "B.Fab")
		)
		(fp_line
			(start 0.12065 -0.2794)
			(end -0.12065 -0.2794)
			(stroke
				(width 0.1)
				(type default)
			)
			(layer "B.Fab")
		)
		(fp_line
			(start 0.12065 0.2794)
			(end 0.12065 0.3048)
			(stroke
				(width 0.1)
				(type default)
			)
			(layer "B.Fab")
		)
		(fp_line
			(start 0.12065 0.3048)
			(end 0.67945 0.3048)
			(stroke
				(width 0.1)
				(type default)
			)
			(layer "B.Fab")
		)
		(fp_line
			(start 0.67945 -0.305054)
			(end 0.12065 -0.305054)
			(stroke
				(width 0.1)
				(type default)
			)
			(layer "B.Fab")
		)
		(fp_line
			(start 0.67945 0.3048)
			(end 0.67945 -0.305054)
			(stroke
				(width 0.1)
				(type default)
			)
			(layer "B.Fab")
		)
		(pad "1" smd circle
			(at 0.40005 0 180)
			(size 0 0)
			(layers "B.Cu" "B.Mask" "B.Paste")
			(net "SMB_S3M_CPU1_PIROM_3V3AUX_SDA")
		)
		(pad "2" smd circle
			(at -0.40005 0 180)
			(size 0 0)
			(layers "B.Cu" "B.Mask" "B.Paste")
			(net "SMB_S3M_CPU1_PIROM_3V3AUX_SDA_1")
		)
	)
	(footprint ""
		(layer "B.Cu")
		(at 60.468002 -8.319262 -90)
		(property "Reference" "R3180"
			(at 0 0 90)
			(layer "B.SilkS")
			(hide yes)
			(effects
				(font
					(size 1.27 1.27)
				)
				(justify mirror)
			)
		)
		(property "Value" ""
			(at 0 0 90)
			(layer "B.Fab")
			(effects
				(font
					(size 1.27 1.27)
				)
				(justify mirror)
			)
		)
		(duplicate_pad_numbers_are_jumpers no)
		(fp_line
			(start -0.7874 0.4064)
			(end 0.7874 0.4064)
			(stroke
				(width 0.1524)
				(type default)
			)
			(layer "B.SilkS")
		)
		(fp_line
			(start 0.7874 0.4064)
			(end 0.7874 -0.4064)
			(stroke
				(width 0.1524)
				(type default)
			)
			(layer "B.SilkS")
		)
		(fp_line
			(start -0.7874 -0.4064)
			(end -0.7874 0.4064)
			(stroke
				(width 0.1524)
				(type default)
			)
			(layer "B.SilkS")
		)
		(fp_line
			(start 0.7874 -0.4064)
			(end -0.7874 -0.4064)
			(stroke
				(width 0.1524)
				(type default)
			)
			(layer "B.SilkS")
		)
		(fp_line
			(start -0.67945 0.3048)
			(end -0.120396 0.3048)
			(stroke
				(width 0.1)
				(type default)
			)
			(layer "B.Fab")
		)
		(fp_line
			(start -0.120396 0.3048)
			(end -0.120396 0.2794)
			(stroke
				(width 0.1)
				(type default)
			)
			(layer "B.Fab")
		)
		(fp_line
			(start 0.12065 0.3048)
			(end 0.67945 0.3048)
			(stroke
				(width 0.1)
				(type default)
			)
			(layer "B.Fab")
		)
		(fp_line
			(start 0.67945 0.3048)
			(end 0.67945 -0.305054)
			(stroke
				(width 0.1)
				(type default)
			)
			(layer "B.Fab")
		)
		(fp_line
			(start -0.120396 0.2794)
			(end 0.12065 0.2794)
			(stroke
				(width 0.1)
				(type default)
			)
			(layer "B.Fab")
		)
		(fp_line
			(start 0.12065 0.2794)
			(end 0.12065 0.3048)
			(stroke
				(width 0.1)
				(type default)
			)
			(layer "B.Fab")
		)
		(fp_line
			(start -0.12065 -0.2794)
			(end -0.12065 -0.3048)
			(stroke
				(width 0.1)
				(type default)
			)
			(layer "B.Fab")
		)
		(fp_line
			(start 0.12065 -0.2794)
			(end -0.12065 -0.2794)
			(stroke
				(width 0.1)
				(type default)
			)
			(layer "B.Fab")
		)
		(fp_line
			(start -0.67945 -0.3048)
			(end -0.67945 0.3048)
			(stroke
				(width 0.1)
				(type default)
			)
			(layer "B.Fab")
		)
		(fp_line
			(start -0.12065 -0.3048)
			(end -0.67945 -0.3048)
			(stroke
				(width 0.1)
				(type default)
			)
			(layer "B.Fab")
		)
		(fp_line
			(start 0.12065 -0.305054)
			(end 0.12065 -0.2794)
			(stroke
				(width 0.1)
				(type default)
			)
			(layer "B.Fab")
		)
		(fp_line
			(start 0.67945 -0.305054)
			(end 0.12065 -0.305054)
			(stroke
				(width 0.1)
				(type default)
			)
			(layer "B.Fab")
		)
		(pad "1" smd circle
			(at 0.40005 0 90)
			(size 0 0)
			(layers "B.Cu" "B.Mask" "B.Paste")
			(net "OCP_V3_1_PRSNTA_R_N")
		)
		(pad "2" smd circle
			(at -0.40005 0 90)
			(size 0 0)
			(layers "B.Cu" "B.Mask" "B.Paste")
			(net "GND")
		)
	)
	(footprint ""
		(layer "B.Cu")
		(at 431.546 -24.094948 -90)
		(property "Reference" "R1898"
			(at 0 0 90)
			(layer "B.SilkS")
			(hide yes)
			(effects
				(font
					(size 1.27 1.27)
				)
				(justify mirror)
			)
		)
		(property "Value" ""
			(at 0 0 90)
			(layer "B.Fab")
			(effects
				(font
					(size 1.27 1.27)
				)
				(justify mirror)
			)
		)
		(duplicate_pad_numbers_are_jumpers no)
		(fp_line
			(start -0.7874 0.4064)
			(end 0.7874 0.4064)
			(stroke
				(width 0.1524)
				(type default)
			)
			(layer "B.SilkS")
		)
		(fp_line
			(start 0.7874 0.4064)
			(end 0.7874 -0.4064)
			(stroke
				(width 0.1524)
				(type default)
			)
			(layer "B.SilkS")
		)
		(fp_line
			(start -0.7874 -0.4064)
			(end -0.7874 0.4064)
			(stroke
				(width 0.1524)
				(type default)
			)
			(layer "B.SilkS")
		)
		(fp_line
			(start 0.7874 -0.4064)
			(end -0.7874 -0.4064)
			(stroke
				(width 0.1524)
				(type default)
			)
			(layer "B.SilkS")
		)
		(fp_line
			(start -0.67945 0.3048)
			(end -0.120396 0.3048)
			(stroke
				(width 0.1)
				(type default)
			)
			(layer "B.Fab")
		)
		(fp_line
			(start -0.120396 0.3048)
			(end -0.120396 0.2794)
			(stroke
				(width 0.1)
				(type default)
			)
			(layer "B.Fab")
		)
		(fp_line
			(start 0.12065 0.3048)
			(end 0.67945 0.3048)
			(stroke
				(width 0.1)
				(type default)
			)
			(layer "B.Fab")
		)
		(fp_line
			(start 0.67945 0.3048)
			(end 0.67945 -0.305054)
			(stroke
				(width 0.1)
				(type default)
			)
			(layer "B.Fab")
		)
		(fp_line
			(start -0.120396 0.2794)
			(end 0.12065 0.2794)
			(stroke
				(width 0.1)
				(type default)
			)
			(layer "B.Fab")
		)
		(fp_line
			(start 0.12065 0.2794)
			(end 0.12065 0.3048)
			(stroke
				(width 0.1)
				(type default)
			)
			(layer "B.Fab")
		)
		(fp_line
			(start -0.12065 -0.2794)
			(end -0.12065 -0.3048)
			(stroke
				(width 0.1)
				(type default)
			)
			(layer "B.Fab")
		)
		(fp_line
			(start 0.12065 -0.2794)
			(end -0.12065 -0.2794)
			(stroke
				(width 0.1)
				(type default)
			)
			(layer "B.Fab")
		)
		(fp_line
			(start -0.67945 -0.3048)
			(end -0.67945 0.3048)
			(stroke
				(width 0.1)
				(type default)
			)
			(layer "B.Fab")
		)
		(fp_line
			(start -0.12065 -0.3048)
			(end -0.67945 -0.3048)
			(stroke
				(width 0.1)
				(type default)
			)
			(layer "B.Fab")
		)
		(fp_line
			(start 0.12065 -0.305054)
			(end 0.12065 -0.2794)
			(stroke
				(width 0.1)
				(type default)
			)
			(layer "B.Fab")
		)
		(fp_line
			(start 0.67945 -0.305054)
			(end 0.12065 -0.305054)
			(stroke
				(width 0.1)
				(type default)
			)
			(layer "B.Fab")
		)
		(pad "1" smd circle
			(at 0.40005 0 90)
			(size 0 0)
			(layers "B.Cu" "B.Mask" "B.Paste")
			(net "OCP_SFF_ISO_BIF2_EN")
		)
		(pad "2" smd circle
			(at -0.40005 0 90)
			(size 0 0)
			(layers "B.Cu" "B.Mask" "B.Paste")
			(net "GND")
		)
	)
	(footprint ""
		(layer "B.Cu")
		(at 34.5313 -319.060068 90)
		(property "Reference" "R898"
			(at 0 0 90)
			(layer "B.SilkS")
			(hide yes)
			(effects
				(font
					(size 1.27 1.27)
				)
				(justify mirror)
			)
		)
		(property "Value" ""
			(at 0 0 90)
			(layer "B.Fab")
			(effects
				(font
					(size 1.27 1.27)
				)
				(justify mirror)
			)
		)
		(duplicate_pad_numbers_are_jumpers no)
		(fp_line
			(start 0.7874 -0.4064)
			(end -0.7874 -0.4064)
			(stroke
				(width 0.1524)
				(type default)
			)
			(layer "B.SilkS")
		)
		(fp_line
			(start -0.7874 -0.4064)
			(end -0.7874 0.4064)
			(stroke
				(width 0.1524)
				(type default)
			)
			(layer "B.SilkS")
		)
		(fp_line
			(start 0.7874 0.4064)
			(end 0.7874 -0.4064)
			(stroke
				(width 0.1524)
				(type default)
			)
			(layer "B.SilkS")
		)
		(fp_line
			(start -0.7874 0.4064)
			(end 0.7874 0.4064)
			(stroke
				(width 0.1524)
				(type default)
			)
			(layer "B.SilkS")
		)
		(fp_line
			(start 0.67945 -0.305054)
			(end 0.12065 -0.305054)
			(stroke
				(width 0.1)
				(type default)
			)
			(layer "B.Fab")
		)
		(fp_line
			(start 0.12065 -0.305054)
			(end 0.12065 -0.2794)
			(stroke
				(width 0.1)
				(type default)
			)
			(layer "B.Fab")
		)
		(fp_line
			(start -0.12065 -0.3048)
			(end -0.67945 -0.3048)
			(stroke
				(width 0.1)
				(type default)
			)
			(layer "B.Fab")
		)
		(fp_line
			(start -0.67945 -0.3048)
			(end -0.67945 0.3048)
			(stroke
				(width 0.1)
				(type default)
			)
			(layer "B.Fab")
		)
		(fp_line
			(start 0.12065 -0.2794)
			(end -0.12065 -0.2794)
			(stroke
				(width 0.1)
				(type default)
			)
			(layer "B.Fab")
		)
		(fp_line
			(start -0.12065 -0.2794)
			(end -0.12065 -0.3048)
			(stroke
				(width 0.1)
				(type default)
			)
			(layer "B.Fab")
		)
		(fp_line
			(start 0.12065 0.2794)
			(end 0.12065 0.3048)
			(stroke
				(width 0.1)
				(type default)
			)
			(layer "B.Fab")
		)
		(fp_line
			(start -0.120396 0.2794)
			(end 0.12065 0.2794)
			(stroke
				(width 0.1)
				(type default)
			)
			(layer "B.Fab")
		)
		(fp_line
			(start 0.67945 0.3048)
			(end 0.67945 -0.305054)
			(stroke
				(width 0.1)
				(type default)
			)
			(layer "B.Fab")
		)
		(fp_line
			(start 0.12065 0.3048)
			(end 0.67945 0.3048)
			(stroke
				(width 0.1)
				(type default)
			)
			(layer "B.Fab")
		)
		(fp_line
			(start -0.120396 0.3048)
			(end -0.120396 0.2794)
			(stroke
				(width 0.1)
				(type default)
			)
			(layer "B.Fab")
		)
		(fp_line
			(start -0.67945 0.3048)
			(end -0.120396 0.3048)
			(stroke
				(width 0.1)
				(type default)
			)
			(layer "B.Fab")
		)
		(pad "1" smd circle
			(at 0.40005 0 270)
			(size 0 0)
			(layers "B.Cu" "B.Mask" "B.Paste")
			(net "PWRGD_CHC_CPU1_DIMM2")
		)
		(pad "2" smd circle
			(at -0.40005 0 270)
			(size 0 0)
			(layers "B.Cu" "B.Mask" "B.Paste")
			(net "PWRGD_FAIL_CPU1_CD")
		)
	)
	(footprint ""
		(layer "B.Cu")
		(at 61.62421 -165.11397)
		(property "Reference" "PC1940"
			(at 0 0 0)
			(layer "B.SilkS")
			(hide yes)
			(effects
				(font
					(size 1.27 1.27)
				)
				(justify mirror)
			)
		)
		(property "Value" ""
			(at 0 0 0)
			(layer "B.Fab")
			(effects
				(font
					(size 1.27 1.27)
				)
				(justify mirror)
			)
		)
		(duplicate_pad_numbers_are_jumpers no)
		(fp_line
			(start -4.53898 -2.15011)
			(end -4.53898 2.15011)
			(stroke
				(width 0.1524)
				(type default)
			)
			(layer "B.SilkS")
		)
		(fp_line
			(start -4.53898 2.15011)
			(end 4.53898 2.15011)
			(stroke
				(width 0.1524)
				(type default)
			)
			(layer "B.SilkS")
		)
		(fp_line
			(start 4.53898 -2.150618)
			(end 4.539742 2.152142)
			(stroke
				(width 0.1524)
				(type default)
			)
			(layer "B.SilkS")
		)
		(fp_line
			(start 4.53898 -2.15011)
			(end -4.53898 -2.15011)
			(stroke
				(width 0.1524)
				(type default)
			)
			(layer "B.SilkS")
		)
		(fp_line
			(start 4.53898 2.15011)
			(end 4.53898 -2.15011)
			(stroke
				(width 0.1524)
				(type default)
			)
			(layer "B.SilkS")
		)
		(fp_line
			(start 4.69138 -2.150618)
			(end 4.692396 2.161032)
			(stroke
				(width 0.1524)
				(type default)
			)
			(layer "B.SilkS")
		)
		(fp_line
			(start 4.83108 2.150364)
			(end 4.447794 2.149348)
			(stroke
				(width 0.1524)
				(type default)
			)
			(layer "B.SilkS")
		)
		(fp_line
			(start 4.84378 -2.150618)
			(end 4.53898 -2.150618)
			(stroke
				(width 0.1524)
				(type default)
			)
			(layer "B.SilkS")
		)
		(fp_line
			(start 4.84378 -2.150618)
			(end 4.842256 2.163064)
			(stroke
				(width 0.1524)
				(type default)
			)
			(layer "B.SilkS")
		)
		(fp_line
			(start -3.64998 -2.15011)
			(end -3.64998 2.15011)
			(stroke
				(width 0.1)
				(type default)
			)
			(layer "B.Fab")
		)
		(fp_line
			(start -3.64998 2.15011)
			(end 3.64998 2.15011)
			(stroke
				(width 0.1)
				(type default)
			)
			(layer "B.Fab")
		)
		(fp_line
			(start 3.64998 -2.15011)
			(end -3.64998 -2.15011)
			(stroke
				(width 0.1)
				(type default)
			)
			(layer "B.Fab")
		)
		(fp_line
			(start 3.64998 2.15011)
			(end 3.64998 -2.15011)
			(stroke
				(width 0.1)
				(type default)
			)
			(layer "B.Fab")
		)
		(fp_text user "-"
			(at -4.94157 0.951992 0)
			(unlocked yes)
			(layer "B.SilkS")
			(effects
				(font
					(size 1.905 1.4224)
					(thickness 0.1524)
				)
				(justify left mirror)
			)
		)
		(fp_text user "+"
			(at 6.214872 -0.337058 0)
			(unlocked yes)
			(layer "B.SilkS")
			(effects
				(font
					(size 1.905 1.4224)
					(thickness 0.1524)
				)
				(justify left mirror)
			)
		)
		(fp_text user "-"
			(at -4.313174 -0.094488 0)
			(unlocked yes)
			(layer "B.Fab")
			(effects
				(font
					(size 1.905 1.4224)
					(thickness 0.1524)
				)
				(justify left mirror)
			)
		)
		(fp_text user "+"
			(at 6.214872 -0.337058 0)
			(unlocked yes)
			(layer "B.Fab")
			(effects
				(font
					(size 1.905 1.4224)
					(thickness 0.1524)
				)
				(justify left mirror)
			)
		)
		(pad "1" smd rect
			(at 3.199892 0 180)
			(size 2.413 2.8194)
			(layers "B.Cu" "B.Mask" "B.Paste")
			(net "PVCCD_HV_CPU1")
		)
		(pad "2" smd rect
			(at -3.199892 0 180)
			(size 2.413 2.8194)
			(layers "B.Cu" "B.Mask" "B.Paste")
			(net "GND")
		)
	)
	(footprint ""
		(layer "B.Cu")
		(at 180.514752 -192.699894 -90)
		(property "Reference" "R326"
			(at 0 0 90)
			(layer "B.SilkS")
			(hide yes)
			(effects
				(font
					(size 1.27 1.27)
				)
				(justify mirror)
			)
		)
		(property "Value" ""
			(at 0 0 90)
			(layer "B.Fab")
			(effects
				(font
					(size 1.27 1.27)
				)
				(justify mirror)
			)
		)
		(duplicate_pad_numbers_are_jumpers no)
		(fp_line
			(start -0.7874 0.4064)
			(end 0.7874 0.4064)
			(stroke
				(width 0.1524)
				(type default)
			)
			(layer "B.SilkS")
		)
		(fp_line
			(start 0.7874 0.4064)
			(end 0.7874 -0.4064)
			(stroke
				(width 0.1524)
				(type default)
			)
			(layer "B.SilkS")
		)
		(fp_line
			(start -0.7874 -0.4064)
			(end -0.7874 0.4064)
			(stroke
				(width 0.1524)
				(type default)
			)
			(layer "B.SilkS")
		)
		(fp_line
			(start 0.7874 -0.4064)
			(end -0.7874 -0.4064)
			(stroke
				(width 0.1524)
				(type default)
			)
			(layer "B.SilkS")
		)
		(fp_line
			(start -0.67945 0.3048)
			(end -0.120396 0.3048)
			(stroke
				(width 0.1)
				(type default)
			)
			(layer "B.Fab")
		)
		(fp_line
			(start -0.120396 0.3048)
			(end -0.120396 0.2794)
			(stroke
				(width 0.1)
				(type default)
			)
			(layer "B.Fab")
		)
		(fp_line
			(start 0.12065 0.3048)
			(end 0.67945 0.3048)
			(stroke
				(width 0.1)
				(type default)
			)
			(layer "B.Fab")
		)
		(fp_line
			(start 0.67945 0.3048)
			(end 0.67945 -0.305054)
			(stroke
				(width 0.1)
				(type default)
			)
			(layer "B.Fab")
		)
		(fp_line
			(start -0.120396 0.2794)
			(end 0.12065 0.2794)
			(stroke
				(width 0.1)
				(type default)
			)
			(layer "B.Fab")
		)
		(fp_line
			(start 0.12065 0.2794)
			(end 0.12065 0.3048)
			(stroke
				(width 0.1)
				(type default)
			)
			(layer "B.Fab")
		)
		(fp_line
			(start -0.12065 -0.2794)
			(end -0.12065 -0.3048)
			(stroke
				(width 0.1)
				(type default)
			)
			(layer "B.Fab")
		)
		(fp_line
			(start 0.12065 -0.2794)
			(end -0.12065 -0.2794)
			(stroke
				(width 0.1)
				(type default)
			)
			(layer "B.Fab")
		)
		(fp_line
			(start -0.67945 -0.3048)
			(end -0.67945 0.3048)
			(stroke
				(width 0.1)
				(type default)
			)
			(layer "B.Fab")
		)
		(fp_line
			(start -0.12065 -0.3048)
			(end -0.67945 -0.3048)
			(stroke
				(width 0.1)
				(type default)
			)
			(layer "B.Fab")
		)
		(fp_line
			(start 0.12065 -0.305054)
			(end 0.12065 -0.2794)
			(stroke
				(width 0.1)
				(type default)
			)
			(layer "B.Fab")
		)
		(fp_line
			(start 0.67945 -0.305054)
			(end 0.12065 -0.305054)
			(stroke
				(width 0.1)
				(type default)
			)
			(layer "B.Fab")
		)
		(pad "1" smd circle
			(at 0.40005 0 90)
			(size 0 0)
			(layers "B.Cu" "B.Mask" "B.Paste")
			(net "P3V3_AUX")
		)
		(pad "2" smd circle
			(at -0.40005 0 90)
			(size 0 0)
			(layers "B.Cu" "B.Mask" "B.Paste")
			(net "PU_S3M_CPU1_CPLD_CONFD")
		)
	)
)
